(kicad_pcb
	(version 20241229)
	(generator "pcbnew")
	(generator_version "9.0")
	(general
		(thickness 1.63)
		(legacy_teardrops no)
	)
	(paper "A4")
	(title_block
		(title "CM4 Baseboard")
		(date "2026-01-05")
		(rev "1.1.1")
		(company "Antmicro Ltd")
		(comment 1 "www.antmicro.com")
		(comment 9 "footprints 225-228 of 506")
	)
	(layers
		(0 "F.Cu" signal)
		(4 "In1.Cu" power)
		(6 "In2.Cu" power)
		(8 "In3.Cu" signal)
		(10 "In4.Cu" signal)
		(2 "B.Cu" signal)
		(9 "F.Adhes" user "F.Adhesive")
		(11 "B.Adhes" user "B.Adhesive")
		(13 "F.Paste" user)
		(15 "B.Paste" user)
		(5 "F.SilkS" user "F.Silkscreen")
		(7 "B.SilkS" user "B.Silkscreen")
		(1 "F.Mask" user)
		(3 "B.Mask" user)
		(17 "Dwgs.User" user "User.Drawings")
		(19 "Cmts.User" user "User.Comments")
		(21 "Eco1.User" user "User.Eco1")
		(23 "Eco2.User" user "User.Eco2")
		(25 "Edge.Cuts" user)
		(27 "Margin" user)
		(31 "F.CrtYd" user "F.Courtyard")
		(29 "B.CrtYd" user "B.Courtyard")
		(35 "F.Fab" user)
		(33 "B.Fab" user)
	)
	(footprint "antmicro-footprints:R_0402_1005Metric"
		(layer "F.Cu")
		(at 98.8 118.65 -90)
		(descr "Resistor SMD 0402")
		(tags "resistor SMD 0402")
		(property "Reference" "R903"
			(at 24.0125 -27.805 90)
			(layer "F.SilkS")
			(effects
				(font
					(size 0.7 0.7)
					(thickness 0.15)
				)
				(justify right bottom)
			)
		)
		(property "Value" "R_910k_0402"
			(at -1.011843 1.772047 90)
			(layer "F.Fab")
			(effects
				(font
					(size 0.7 0.7)
					(thickness 0.15)
				)
				(justify right bottom)
			)
		)
		(property "Datasheet" "https://www.bourns.com/docs/product-datasheets/cr.pdf"
			(at 0 0 270)
			(layer "F.Fab")
			(hide yes)
			(effects
				(font
					(size 1.27 1.27)
					(thickness 0.15)
				)
			)
		)
		(property "MPN" "CR0402-FX-9103GLF"
			(at 0 0 270)
			(unlocked yes)
			(layer "F.Fab")
			(hide yes)
			(effects
				(font
					(size 1 1)
					(thickness 0.15)
				)
			)
		)
		(property "Manufacturer" "Bourns"
			(at 0 0 270)
			(unlocked yes)
			(layer "F.Fab")
			(hide yes)
			(effects
				(font
					(size 1 1)
					(thickness 0.15)
				)
			)
		)
		(property "License" "Apache-2.0"
			(at 0 0 270)
			(unlocked yes)
			(layer "F.Fab")
			(hide yes)
			(effects
				(font
					(size 1 1)
					(thickness 0.15)
				)
			)
		)
		(property "Author" "Antmicro"
			(at 0 0 270)
			(unlocked yes)
			(layer "F.Fab")
			(hide yes)
			(effects
				(font
					(size 1 1)
					(thickness 0.15)
				)
			)
		)
		(property "Val" "910k"
			(at 0 0 270)
			(unlocked yes)
			(layer "F.Fab")
			(hide yes)
			(effects
				(font
					(size 1 1)
					(thickness 0.15)
				)
			)
		)
		(property "Tolerance" "1%"
			(at 0 0 270)
			(unlocked yes)
			(layer "F.Fab")
			(hide yes)
			(effects
				(font
					(size 1 1)
					(thickness 0.15)
				)
			)
		)
		(sheetname "/USB/")
		(sheetfile "usb.kicad_sch")
		(attr smd)
		(fp_rect
			(start -0.925 -0.47)
			(end 0.925 0.47)
			(stroke
				(width 0.05)
				(type default)
			)
			(fill no)
			(layer "F.CrtYd")
		)
		(fp_rect
			(start -0.5 -0.25)
			(end 0.5 0.25)
			(stroke
				(width 0.15)
				(type solid)
			)
			(fill no)
			(layer "F.Fab")
		)
		(fp_text user "Author: Antmicro"
			(at -0.95 4.169 270)
			(layer "F.Fab")
			(effects
				(font
					(size 0.7 0.7)
					(thickness 0.15)
				)
				(justify left bottom)
			)
		)
		(fp_text user "${REFERENCE}"
			(at -0.95 3.168 270)
			(layer "F.Fab")
			(effects
				(font
					(size 0.7 0.7)
					(thickness 0.15)
				)
				(justify left bottom)
			)
		)
		(fp_text user "License: Apache-2.0"
			(at -0.95 5.169 270)
			(layer "F.Fab")
			(effects
				(font
					(size 0.7 0.7)
					(thickness 0.15)
				)
				(justify left bottom)
			)
		)
		(pad "1" smd roundrect
			(at -0.48 0 270)
			(size 0.59 0.64)
			(layers "F.Cu" "F.Mask" "F.Paste")
			(roundrect_rratio 0.25)
			(net 24 "/Compute module/USBA_VBUS")
			(pintype "passive")
		)
		(pad "2" smd roundrect
			(at 0.48 0 270)
			(size 0.59 0.64)
			(layers "F.Cu" "F.Mask" "F.Paste")
			(roundrect_rratio 0.25)
			(net 340 "Net-(U906-VBUS_DET)")
			(pintype "passive")
		)
	)
	(footprint "antmicro-footprints:C_0402_1005Metric"
		(layer "F.Cu")
		(at 85.242962 132.5915)
		(descr "Capacitor SMD 0402")
		(tags "capacitor SMD 0402")
		(property "Reference" "C903"
			(at -2.835 -0.845 0)
			(layer "F.SilkS")
			(effects
				(font
					(size 0.7 0.7)
					(thickness 0.15)
				)
				(justify left bottom)
			)
		)
		(property "Value" "C_100n_0402"
			(at -1.022927 2.155213 0)
			(layer "F.Fab")
			(effects
				(font
					(size 0.7 0.7)
					(thickness 0.15)
				)
				(justify left bottom)
			)
		)
		(property "Datasheet" "https://www.murata.com/products/productdetail?partno=GRM155R61H104KE14%23"
			(at 0 0 0)
			(layer "F.Fab")
			(hide yes)
			(effects
				(font
					(size 1.27 1.27)
					(thickness 0.15)
				)
			)
		)
		(property "Manufacturer" "Murata"
			(at 0 0 0)
			(unlocked yes)
			(layer "F.Fab")
			(hide yes)
			(effects
				(font
					(size 1 1)
					(thickness 0.15)
				)
			)
		)
		(property "MPN" "GRM155R61H104KE14D"
			(at 0 0 0)
			(unlocked yes)
			(layer "F.Fab")
			(hide yes)
			(effects
				(font
					(size 1 1)
					(thickness 0.15)
				)
			)
		)
		(property "Val" "100n"
			(at 0 0 0)
			(unlocked yes)
			(layer "F.Fab")
			(hide yes)
			(effects
				(font
					(size 1 1)
					(thickness 0.15)
				)
			)
		)
		(property "License" "Apache-2.0"
			(at 0 0 0)
			(unlocked yes)
			(layer "F.Fab")
			(hide yes)
			(effects
				(font
					(size 1 1)
					(thickness 0.15)
				)
			)
		)
		(property "Author" "Antmicro"
			(at 0 0 0)
			(unlocked yes)
			(layer "F.Fab")
			(hide yes)
			(effects
				(font
					(size 1 1)
					(thickness 0.15)
				)
			)
		)
		(property "Voltage" "50V"
			(at 0 0 0)
			(unlocked yes)
			(layer "F.Fab")
			(hide yes)
			(effects
				(font
					(size 1 1)
					(thickness 0.15)
				)
			)
		)
		(property "Dielectric" "X5R"
			(at 0 0 0)
			(unlocked yes)
			(layer "F.Fab")
			(hide yes)
			(effects
				(font
					(size 1 1)
					(thickness 0.15)
				)
			)
		)
		(sheetname "/USB/")
		(sheetfile "usb.kicad_sch")
		(attr smd)
		(fp_rect
			(start -0.925 -0.47)
			(end 0.925 0.47)
			(stroke
				(width 0.05)
				(type default)
			)
			(fill no)
			(layer "F.CrtYd")
		)
		(fp_line
			(start -0.494 -0.25)
			(end 0.504 -0.25)
			(stroke
				(width 0.15)
				(type solid)
			)
			(layer "F.Fab")
		)
		(fp_line
			(start -0.494 0.248)
			(end -0.494 -0.25)
			(stroke
				(width 0.15)
				(type solid)
			)
			(layer "F.Fab")
		)
		(fp_line
			(start 0.504 -0.25)
			(end 0.504 0.248)
			(stroke
				(width 0.15)
				(type solid)
			)
			(layer "F.Fab")
		)
		(fp_line
			(start 0.504 0.248)
			(end -0.494 0.248)
			(stroke
				(width 0.15)
				(type solid)
			)
			(layer "F.Fab")
		)
		(fp_text user "${REFERENCE}"
			(at -0.939 4.599 0)
			(layer "F.Fab")
			(effects
				(font
					(size 0.7 0.7)
					(thickness 0.15)
				)
				(justify left bottom)
			)
		)
		(fp_text user "Author: Antmicro"
			(at -0.939 3.399 0)
			(layer "F.Fab")
			(effects
				(font
					(size 0.7 0.7)
					(thickness 0.15)
				)
				(justify left bottom)
			)
		)
		(fp_text user "License: Apache-2.0"
			(at -0.939 5.799 0)
			(layer "F.Fab")
			(effects
				(font
					(size 0.7 0.7)
					(thickness 0.15)
				)
				(justify left bottom)
			)
		)
		(pad "1" smd roundrect
			(at -0.48 0)
			(size 0.59 0.64)
			(layers "F.Cu" "F.Mask" "F.Paste")
			(roundrect_rratio 0.25)
			(net 27 "/USB/USB_3V3")
			(pintype "passive")
		)
		(pad "2" smd roundrect
			(at 0.48 0)
			(size 0.59 0.64)
			(layers "F.Cu" "F.Mask" "F.Paste")
			(roundrect_rratio 0.25)
			(net 3 "GND")
			(pintype "passive")
		)
	)
	(footprint "antmicro-footprints:SOT-23-3"
		(layer "F.Cu")
		(at 104.892962 154.792)
		(property "Reference" "Q205"
			(at -2.045 -1.6155 0)
			(layer "F.SilkS")
			(effects
				(font
					(size 0.7 0.7)
					(thickness 0.15)
				)
				(justify left bottom)
			)
		)
		(property "Value" "SSM3J332R"
			(at -1.9 2.7 0)
			(layer "F.Fab")
			(effects
				(font
					(size 0.7 0.7)
					(thickness 0.15)
				)
				(justify left bottom)
			)
		)
		(property "Datasheet" "https://www.mouser.com/datasheet/2/408/SSM3J332R_datasheet_en_20181015-1150575.pdf"
			(at 0 0 0)
			(layer "F.Fab")
			(hide yes)
			(effects
				(font
					(size 1.27 1.27)
					(thickness 0.15)
				)
			)
		)
		(property "MPN" "SSM3J332R,LF"
			(at 0 0 0)
			(unlocked yes)
			(layer "F.Fab")
			(hide yes)
			(effects
				(font
					(size 1 1)
					(thickness 0.15)
				)
			)
		)
		(property "Manufacturer" "Toshiba"
			(at 0 0 0)
			(unlocked yes)
			(layer "F.Fab")
			(hide yes)
			(effects
				(font
					(size 1 1)
					(thickness 0.15)
				)
			)
		)
		(property "Author" "Antmicro"
			(at 0 0 0)
			(unlocked yes)
			(layer "F.Fab")
			(hide yes)
			(effects
				(font
					(size 1 1)
					(thickness 0.15)
				)
			)
		)
		(property "License" "Apache-2.0"
			(at 0 0 0)
			(unlocked yes)
			(layer "F.Fab")
			(hide yes)
			(effects
				(font
					(size 1 1)
					(thickness 0.15)
				)
			)
		)
		(sheetname "/Compute module/")
		(sheetfile "compute-module.kicad_sch")
		(attr smd)
		(fp_line
			(start -1.45 -1.35)
			(end -0.85 -1.35)
			(stroke
				(width 0.15)
				(type solid)
			)
			(layer "F.SilkS")
		)
		(fp_line
			(start -0.85 -1.35)
			(end -0.7 -1.5)
			(stroke
				(width 0.15)
				(type solid)
			)
			(layer "F.SilkS")
		)
		(fp_line
			(start -0.7 1.5)
			(end -0.7 1.35)
			(stroke
				(width 0.15)
				(type solid)
			)
			(layer "F.SilkS")
		)
		(fp_line
			(start 0.7 -1.5)
			(end -0.7 -1.5)
			(stroke
				(width 0.15)
				(type solid)
			)
			(layer "F.SilkS")
		)
		(fp_line
			(start 0.7 -0.4)
			(end 0.7 -1.5)
			(stroke
				(width 0.15)
				(type solid)
			)
			(layer "F.SilkS")
		)
		(fp_line
			(start 0.7 0.4)
			(end 0.7 1.5)
			(stroke
				(width 0.15)
				(type solid)
			)
			(layer "F.SilkS")
		)
		(fp_line
			(start 0.7 1.5)
			(end -0.7 1.5)
			(stroke
				(width 0.15)
				(type solid)
			)
			(layer "F.SilkS")
		)
		(fp_line
			(start -1.75 -0.5)
			(end -1.75 -1.4)
			(stroke
				(width 0.05)
				(type solid)
			)
			(layer "F.CrtYd")
		)
		(fp_line
			(start -1.75 0.5)
			(end -0.85 0.5)
			(stroke
				(width 0.05)
				(type solid)
			)
			(layer "F.CrtYd")
		)
		(fp_line
			(start -1.75 1.4)
			(end -1.75 0.5)
			(stroke
				(width 0.05)
				(type solid)
			)
			(layer "F.CrtYd")
		)
		(fp_line
			(start -0.9 -1.6)
			(end -0.9 -1.4)
			(stroke
				(width 0.05)
				(type solid)
			)
			(layer "F.CrtYd")
		)
		(fp_line
			(start -0.9 -1.6)
			(end 0.825 -1.6)
			(stroke
				(width 0.05)
				(type solid)
			)
			(layer "F.CrtYd")
		)
		(fp_line
			(start -0.9 -1.4)
			(end -1.75 -1.4)
			(stroke
				(width 0.05)
				(type solid)
			)
			(layer "F.CrtYd")
		)
		(fp_line
			(start -0.85 -0.5)
			(end -1.75 -0.5)
			(stroke
				(width 0.05)
				(type solid)
			)
			(layer "F.CrtYd")
		)
		(fp_line
			(start -0.85 0.5)
			(end -0.85 -0.5)
			(stroke
				(width 0.05)
				(type solid)
			)
			(layer "F.CrtYd")
		)
		(fp_line
			(start -0.85 1.4)
			(end -1.75 1.4)
			(stroke
				(width 0.05)
				(type solid)
			)
			(layer "F.CrtYd")
		)
		(fp_line
			(start -0.85 1.65)
			(end -0.85 1.4)
			(stroke
				(width 0.05)
				(type solid)
			)
			(layer "F.CrtYd")
		)
		(fp_line
			(start 0.825 -1.6)
			(end 0.825 -0.45)
			(stroke
				(width 0.05)
				(type solid)
			)
			(layer "F.CrtYd")
		)
		(fp_line
			(start 0.825 -0.45)
			(end 1.75 -0.45)
			(stroke
				(width 0.05)
				(type solid)
			)
			(layer "F.CrtYd")
		)
		(fp_line
			(start 0.85 0.45)
			(end 0.85 1.65)
			(stroke
				(width 0.05)
				(type solid)
			)
			(layer "F.CrtYd")
		)
		(fp_line
			(start 0.85 1.65)
			(end -0.85 1.65)
			(stroke
				(width 0.05)
				(type solid)
			)
			(layer "F.CrtYd")
		)
		(fp_line
			(start 1.75 -0.45)
			(end 1.75 0.45)
			(stroke
				(width 0.05)
				(type solid)
			)
			(layer "F.CrtYd")
		)
		(fp_line
			(start 1.75 0.45)
			(end 0.85 0.45)
			(stroke
				(width 0.05)
				(type solid)
			)
			(layer "F.CrtYd")
		)
		(fp_line
			(start -0.712 -1.325)
			(end -0.712 1.523)
			(stroke
				(width 0.15)
				(type solid)
			)
			(layer "F.Fab")
		)
		(fp_line
			(start -0.712 1.519)
			(end 0.688 1.519)
			(stroke
				(width 0.15)
				(type solid)
			)
			(layer "F.Fab")
		)
		(fp_line
			(start -0.437 -1.526)
			(end -0.712 -1.325)
			(stroke
				(width 0.15)
				(type solid)
			)
			(layer "F.Fab")
		)
		(fp_line
			(start -0.437 -1.526)
			(end 0.688 -1.526)
			(stroke
				(width 0.15)
				(type solid)
			)
			(layer "F.Fab")
		)
		(fp_line
			(start 0.688 1.519)
			(end 0.688 -1.52)
			(stroke
				(width 0.15)
				(type solid)
			)
			(layer "F.Fab")
		)
		(fp_text user "${REFERENCE}"
			(at -1.837 4 0)
			(layer "F.Fab")
			(effects
				(font
					(size 0.7 0.7)
					(thickness 0.15)
				)
				(justify left bottom)
			)
		)
		(fp_text user "License: Apache-2.0"
			(at -1.8 6.8 0)
			(layer "F.Fab")
			(effects
				(font
					(size 0.7 0.7)
					(thickness 0.15)
				)
				(justify left bottom)
			)
		)
		(fp_text user "Author: Antmicro"
			(at -1.837 5.3 0)
			(layer "F.Fab")
			(effects
				(font
					(size 0.7 0.7)
					(thickness 0.15)
				)
				(justify left bottom)
			)
		)
		(pad "1" smd roundrect
			(at -1.1 -0.951)
			(size 1 0.6)
			(layers "F.Cu" "F.Mask" "F.Paste")
			(roundrect_rratio 0.15)
			(net 327 "Net-(Q201-D)")
			(pinfunction "G")
			(pintype "input")
		)
		(pad "2" smd roundrect
			(at -1.1 0.949)
			(size 1 0.6)
			(layers "F.Cu" "F.Mask" "F.Paste")
			(roundrect_rratio 0.15)
			(net 10 "+5V")
			(pinfunction "S")
			(pintype "passive")
		)
		(pad "3" smd roundrect
			(at 1.1 -0.0005)
			(size 1 0.6)
			(layers "F.Cu" "F.Mask" "F.Paste")
			(roundrect_rratio 0.15)
			(net 260 "/Compute module/Pf_5V.CEC")
			(pinfunction "D")
			(pintype "passive")
		)
	)
	(footprint "antmicro-footprints:Nexperia_DFN-10_2.5x1mm_P0.5mm"
		(layer "F.Cu")
		(at 134.067962 147.1665 90)
		(property "Reference" "D808"
			(at -1.298 -1.562 90)
			(layer "F.SilkS")
			(effects
				(font
					(size 0.7 0.7)
					(thickness 0.15)
				)
				(justify left bottom)
			)
		)
		(property "Value" "PUSB3F96X_PASS"
			(at -0.016 1.705 90)
			(layer "F.Fab")
			(effects
				(font
					(size 0.7 0.7)
					(thickness 0.15)
				)
				(justify left bottom)
			)
		)
		(property "Datasheet" "https://mouser.com/datasheet/2/916/PUSB3F96-1600324.pdf"
			(at 0 0 90)
			(layer "F.Fab")
			(hide yes)
			(effects
				(font
					(size 1.27 1.27)
					(thickness 0.15)
				)
			)
		)
		(property "Manufacturer" "Nexperia"
			(at 0 0 90)
			(unlocked yes)
			(layer "F.Fab")
			(hide yes)
			(effects
				(font
					(size 1 1)
					(thickness 0.15)
				)
			)
		)
		(property "MPN" "PUSB3F96X"
			(at 0 0 90)
			(unlocked yes)
			(layer "F.Fab")
			(hide yes)
			(effects
				(font
					(size 1 1)
					(thickness 0.15)
				)
			)
		)
		(property "Author" "Antmicro"
			(at 0 0 90)
			(unlocked yes)
			(layer "F.Fab")
			(hide yes)
			(effects
				(font
					(size 1 1)
					(thickness 0.15)
				)
			)
		)
		(property "License" "Apache-2.0"
			(at 0 0 90)
			(unlocked yes)
			(layer "F.Fab")
			(hide yes)
			(effects
				(font
					(size 1 1)
					(thickness 0.15)
				)
			)
		)
		(sheetname "/Peripherals/")
		(sheetfile "peripherals.kicad_sch")
		(attr smd)
		(fp_line
			(start -1.375 -0.4)
			(end -1.375 0.4)
			(stroke
				(width 0.15)
				(type solid)
			)
			(layer "F.SilkS")
		)
		(fp_line
			(start 1.375 0.4)
			(end 1.375 -0.4)
			(stroke
				(width 0.15)
				(type solid)
			)
			(layer "F.SilkS")
		)
		(fp_circle
			(center -1.4 0.7)
			(end -1.349 0.7)
			(stroke
				(width 0.15)
				(type solid)
			)
			(fill yes)
			(layer "F.SilkS")
		)
		(fp_rect
			(start -1.4 -0.725)
			(end 1.4 0.725)
			(stroke
				(width 0.05)
				(type solid)
			)
			(fill no)
			(layer "F.CrtYd")
		)
		(fp_line
			(start 1.25 -0.5)
			(end -1.25 -0.5)
			(stroke
				(width 0.15)
				(type solid)
			)
			(layer "F.Fab")
		)
		(fp_line
			(start -1.25 -0.5)
			(end -1.25 0.15)
			(stroke
				(width 0.15)
				(type solid)
			)
			(layer "F.Fab")
		)
		(fp_line
			(start -1.25 0.15)
			(end -0.9 0.5)
			(stroke
				(width 0.15)
				(type solid)
			)
			(layer "F.Fab")
		)
		(fp_line
			(start 1.25 0.5)
			(end 1.25 -0.5)
			(stroke
				(width 0.15)
				(type solid)
			)
			(layer "F.Fab")
		)
		(fp_line
			(start -0.9 0.5)
			(end 1.25 0.5)
			(stroke
				(width 0.15)
				(type solid)
			)
			(layer "F.Fab")
		)
		(fp_text user "${REFERENCE}"
			(at -1.367 3.704 90)
			(layer "F.Fab")
			(effects
				(font
					(size 0.7 0.7)
					(thickness 0.15)
				)
				(justify left bottom)
			)
		)
		(fp_text user "Author: Antmicro"
			(at -1.367 4.905 90)
			(layer "F.Fab")
			(effects
				(font
					(size 0.7 0.7)
					(thickness 0.15)
				)
				(justify left bottom)
			)
		)
		(fp_text user "License: Apache-2.0"
			(at -1.367 6.105 90)
			(layer "F.Fab")
			(effects
				(font
					(size 0.7 0.7)
					(thickness 0.15)
				)
				(justify left bottom)
			)
		)
		(pad "1" smd rect
			(at -1 0.3875 90)
			(size 0.2 0.475)
			(layers "F.Cu" "F.Mask" "F.Paste")
			(net 251 "/Compute module/GPIO.AIN1")
			(pinfunction "CH1")
			(pintype "passive")
			(solder_mask_margin 0.05)
		)
		(pad "2" smd rect
			(at -0.5 0.3875 90)
			(size 0.2 0.475)
			(layers "F.Cu" "F.Mask" "F.Paste")
			(net 235 "/Compute module/GPIO.23")
			(pinfunction "CH2")
			(pintype "passive")
			(solder_mask_margin 0.05)
		)
		(pad "3" smd rect
			(at 0 0.3875 90)
			(size 0.2 0.475)
			(layers "F.Cu" "F.Mask" "F.Paste")
			(net 3 "GND")
			(pinfunction "GND")
			(pintype "passive")
			(solder_mask_margin 0.05)
		)
		(pad "4" smd rect
			(at 0.5 0.3875 90)
			(size 0.2 0.475)
			(layers "F.Cu" "F.Mask" "F.Paste")
			(net 233 "/Compute module/GPIO.24")
			(pinfunction "CH3")
			(pintype "passive")
			(solder_mask_margin 0.05)
		)
		(pad "5" smd rect
			(at 1 0.3875 90)
			(size 0.2 0.475)
			(layers "F.Cu" "F.Mask" "F.Paste")
			(net 230 "/Compute module/GPIO.25")
			(pinfunction "CH4")
			(pintype "passive")
			(solder_mask_margin 0.05)
		)
		(pad "6" smd rect
			(at 1 -0.3875 90)
			(size 0.2 0.475)
			(layers "F.Cu" "F.Mask" "F.Paste")
			(net 230 "/Compute module/GPIO.25")
			(pinfunction "CH4")
			(pintype "passive")
			(solder_mask_margin 0.05)
		)
		(pad "7" smd rect
			(at 0.5 -0.3875 90)
			(size 0.2 0.475)
			(layers "F.Cu" "F.Mask" "F.Paste")
			(net 233 "/Compute module/GPIO.24")
			(pinfunction "CH3")
			(pintype "passive")
			(solder_mask_margin 0.05)
		)
		(pad "8" smd rect
			(at 0 -0.3875 90)
			(size 0.2 0.475)
			(layers "F.Cu" "F.Mask" "F.Paste")
			(net 3 "GND")
			(pinfunction "GND")
			(pintype "passive")
			(solder_mask_margin 0.05)
		)
		(pad "9" smd rect
			(at -0.501 -0.3875 90)
			(size 0.2 0.475)
			(layers "F.Cu" "F.Mask" "F.Paste")
			(net 235 "/Compute module/GPIO.23")
			(pinfunction "CH2")
			(pintype "passive")
			(solder_mask_margin 0.05)
		)
		(pad "10" smd rect
			(at -1 -0.3875 90)
			(size 0.2 0.475)
			(layers "F.Cu" "F.Mask" "F.Paste")
			(net 251 "/Compute module/GPIO.AIN1")
			(pinfunction "CH1")
			(pintype "passive")
			(solder_mask_margin 0.05)
		)
	)
)
